(kicad_pcb
	(version 20260206)
	(generator "pcbnew")
	(generator_version "10.0")
	(general
		(thickness 1.6)
		(legacy_teardrops no)
	)
	(paper "A4")
	(title_block
		(title "01162023_DA0F0TEBIF0_F0T_Expander_BD_F_brd_V02_OCP.brd")
		(comment 1 "Grand Teton / footprints 4891-4892 of 9728")
	)
	(layers
		(0 "F.Cu" signal "TOP")
		(4 "In1.Cu" signal "GND")
		(6 "In2.Cu" signal "VCC")
		(8 "In3.Cu" signal "VCC1")
		(10 "In4.Cu" signal "GND1")
		(12 "In5.Cu" signal "IN1")
		(14 "In6.Cu" signal "GND2")
		(16 "In7.Cu" signal "IN2")
		(18 "In8.Cu" signal "GND3")
		(20 "In9.Cu" signal "IN3")
		(22 "In10.Cu" signal "GND4")
		(24 "In11.Cu" signal "IN4")
		(26 "In12.Cu" signal "GND5")
		(28 "In13.Cu" signal "IN5")
		(30 "In14.Cu" signal "GND6")
		(32 "In15.Cu" signal "IN6")
		(34 "In16.Cu" signal "GND7")
		(2 "B.Cu" signal "BOTTOM")
		(9 "F.Adhes" user "F.Adhesive")
		(11 "B.Adhes" user "B.Adhesive")
		(13 "F.Paste" user "Package Geometry/Pastemask Top")
		(15 "B.Paste" user "Package Geometry/Pastemask Bottom")
		(5 "F.SilkS" user "Ref Des/Silkscreen Top")
		(7 "B.SilkS" user "Ref Des/Silkscreen Bottom")
		(1 "F.Mask" user "Board Geometry/Soldermask Top")
		(3 "B.Mask" user "Board Geometry/Soldermask Bottom")
		(17 "Dwgs.User" user "User.Drawings")
		(19 "Cmts.User" user "User.Comments")
		(21 "Eco1.User" user "User.Eco1")
		(23 "Eco2.User" user "User.Eco2")
		(25 "Edge.Cuts" user "Board Geometry/Outline")
		(27 "Margin" user)
		(31 "F.CrtYd" user "Package Geometry/Place Bound Top")
		(29 "B.CrtYd" user "Package Geometry/Place Bound Bottom")
		(35 "F.Fab" user "Ref Des/Assembly Top")
		(33 "B.Fab" user "Ref Des/Assembly Bottom")
	)
	(footprint ""
		(layer "F.Cu")
		(at 129.06502 -26.785062 180)
		(property "Reference" "J34"
			(at 3.89255 -10.986262 90)
			(unlocked yes)
			(layer "F.SilkS")
			(effects
				(font
					(size 0.7874 0.5842)
					(thickness 0.1524)
				)
			)
		)
		(property "Value" ""
			(at 0 0 180)
			(layer "F.Fab")
			(effects
				(font
					(size 1.27 1.27)
				)
			)
		)
		(duplicate_pad_numbers_are_jumpers no)
		(fp_line
			(start 3.150108 12.115038)
			(end 1.529334 12.115038)
			(stroke
				(width 0.1524)
				(type default)
			)
			(layer "F.SilkS")
		)
		(fp_line
			(start 3.074924 12.014962)
			(end 1.632204 12.014962)
			(stroke
				(width 0.1524)
				(type default)
			)
			(layer "F.SilkS")
		)
		(fp_line
			(start 1.632204 -12.014962)
			(end 3.074924 -12.014962)
			(stroke
				(width 0.1524)
				(type default)
			)
			(layer "F.SilkS")
		)
		(fp_line
			(start 1.529334 -12.115038)
			(end 3.150108 -12.115038)
			(stroke
				(width 0.1524)
				(type default)
			)
			(layer "F.SilkS")
		)
		(fp_line
			(start -1.529334 12.115038)
			(end -3.150108 12.115038)
			(stroke
				(width 0.1524)
				(type default)
			)
			(layer "F.SilkS")
		)
		(fp_line
			(start -1.632204 12.014962)
			(end -3.074924 12.014962)
			(stroke
				(width 0.1524)
				(type default)
			)
			(layer "F.SilkS")
		)
		(fp_line
			(start -3.074924 -12.014962)
			(end -1.632204 -12.014962)
			(stroke
				(width 0.1524)
				(type default)
			)
			(layer "F.SilkS")
		)
		(fp_line
			(start -3.150108 -12.115038)
			(end -1.529334 -12.115038)
			(stroke
				(width 0.1524)
				(type default)
			)
			(layer "F.SilkS")
		)
		(fp_poly
			(pts
				(xy 4.00812 -8.835136) (xy 4.430522 -10.10285) (xy 5.27558 -9.257792)
			)
			(stroke
				(width 0)
				(type default)
			)
			(fill yes)
			(layer "F.SilkS")
		)
		(fp_line
			(start 3.074924 12.014962)
			(end -3.074924 12.014962)
			(stroke
				(width 0.1)
				(type default)
			)
			(layer "F.Fab")
		)
		(fp_line
			(start 3.074924 -12.014962)
			(end 3.074924 12.014962)
			(stroke
				(width 0.1)
				(type default)
			)
			(layer "F.Fab")
		)
		(fp_line
			(start -3.074924 12.014962)
			(end -3.074924 -12.014962)
			(stroke
				(width 0.1)
				(type default)
			)
			(layer "F.Fab")
		)
		(fp_line
			(start -3.074924 -12.014962)
			(end 3.074924 -12.014962)
			(stroke
				(width 0.1)
				(type default)
			)
			(layer "F.Fab")
		)
		(fp_poly
			(pts
				(xy 3.348736 -7.994904) (xy 4.543806 -8.592566) (xy 4.543806 -7.397496)
			)
			(stroke
				(width 0)
				(type default)
			)
			(fill yes)
			(layer "F.Fab")
		)
		(pad "" np_thru_hole circle
			(at -1.75006 -9.815068 90)
			(size 1.1176 1.1176)
			(drill 1.1176)
			(layers "*.Cu" "*.Mask")
			(clearance 0.381)
			(thermal_gap 0.381)
		)
		(pad "" np_thru_hole circle
			(at 0 9.815068 90)
			(size 1.1176 1.1176)
			(drill 1.1176)
			(layers "*.Cu" "*.Mask")
			(clearance 0.381)
			(thermal_gap 0.381)
		)
		(pad "A1" smd rect
			(at 2.29997 -7.994904 90)
			(size 0.381 1.27)
			(layers "F.Cu" "F.Mask" "F.Paste")
			(net "GND")
		)
		(pad "A2" smd rect
			(at 2.29997 -7.394956 90)
			(size 0.381 1.27)
			(layers "F.Cu" "F.Mask" "F.Paste")
			(net "GND")
		)
		(pad "A3" smd rect
			(at 2.29997 -6.795008 90)
			(size 0.381 1.27)
			(layers "F.Cu" "F.Mask" "F.Paste")
			(net "GND")
		)
		(pad "A4" smd rect
			(at 2.29997 -6.19506 90)
			(size 0.381 1.27)
			(layers "F.Cu" "F.Mask" "F.Paste")
			(net "GND")
		)
		(pad "A5" smd rect
			(at 2.29997 -5.595112 90)
			(size 0.381 1.27)
			(layers "F.Cu" "F.Mask" "F.Paste")
			(net "GND")
		)
		(pad "A6" smd rect
			(at 2.29997 -4.99491 90)
			(size 0.381 1.27)
			(layers "F.Cu" "F.Mask" "F.Paste")
			(net "GND")
		)
		(pad "A7" smd rect
			(at 2.29997 -4.394962 90)
			(size 0.381 1.27)
			(layers "F.Cu" "F.Mask" "F.Paste")
			(net "SMB_ISO_SSD4_R_SCL")
		)
		(pad "A8" smd rect
			(at 2.29997 -3.795014 90)
			(size 0.381 1.27)
			(layers "F.Cu" "F.Mask" "F.Paste")
			(net "SMB_ISO_SSD4_R_SDA")
		)
		(pad "A9" smd rect
			(at 2.29997 -3.195066 90)
			(size 0.381 1.27)
			(layers "F.Cu" "F.Mask" "F.Paste")
			(net "RST_SMB_SSD4_ISO_R_N")
		)
		(pad "A10" smd rect
			(at 2.29997 -2.595118 90)
			(size 0.381 1.27)
			(layers "F.Cu" "F.Mask" "F.Paste")
			(net "SSD4_LED_ISO_R_N")
		)
		(pad "A11" smd rect
			(at 2.29997 -1.994916 90)
			(size 0.381 1.27)
			(layers "F.Cu" "F.Mask" "F.Paste")
			(net "PU_CLKREQ4")
		)
		(pad "A12" smd rect
			(at 2.29997 -1.394968 90)
			(size 0.381 1.27)
			(layers "F.Cu" "F.Mask" "F.Paste")
			(net "PRSNT_SSD4_N")
		)
		(pad "A13" smd rect
			(at 2.29997 -0.79502 90)
			(size 0.381 1.27)
			(layers "F.Cu" "F.Mask" "F.Paste")
			(net "GND")
		)
		(pad "A14" smd rect
			(at 2.29997 -0.195072 90)
			(size 0.381 1.27)
			(layers "F.Cu" "F.Mask" "F.Paste")
			(net "Net_8525")
		)
		(pad "A15" smd rect
			(at 2.29997 0.404876 90)
			(size 0.381 1.27)
			(layers "F.Cu" "F.Mask" "F.Paste")
			(net "Net_8524")
		)
		(pad "A16" smd rect
			(at 2.29997 1.005078 90)
			(size 0.381 1.27)
			(layers "F.Cu" "F.Mask" "F.Paste")
			(net "GND")
		)
		(pad "A17" smd rect
			(at 2.29997 1.605026 90)
			(size 0.381 1.27)
			(layers "F.Cu" "F.Mask" "F.Paste")
			(net "P5E_PEX1_STN2_RX_DN<44>")
		)
		(pad "A18" smd rect
			(at 2.29997 2.204974 90)
			(size 0.381 1.27)
			(layers "F.Cu" "F.Mask" "F.Paste")
			(net "P5E_PEX1_STN2_RX_DP<44>")
		)
		(pad "A19" smd rect
			(at 2.29997 2.804922 90)
			(size 0.381 1.27)
			(layers "F.Cu" "F.Mask" "F.Paste")
			(net "GND")
		)
		(pad "A20" smd rect
			(at 2.29997 3.405124 90)
			(size 0.381 1.27)
			(layers "F.Cu" "F.Mask" "F.Paste")
			(net "P5E_PEX1_STN2_RX_DN<45>")
		)
		(pad "A21" smd rect
			(at 2.29997 4.005072 90)
			(size 0.381 1.27)
			(layers "F.Cu" "F.Mask" "F.Paste")
			(net "P5E_PEX1_STN2_RX_DP<45>")
		)
		(pad "A22" smd rect
			(at 2.29997 4.60502 90)
			(size 0.381 1.27)
			(layers "F.Cu" "F.Mask" "F.Paste")
			(net "GND")
		)
		(pad "A23" smd rect
			(at 2.29997 5.204968 90)
			(size 0.381 1.27)
			(layers "F.Cu" "F.Mask" "F.Paste")
			(net "P5E_PEX1_STN2_RX_DN<46>")
		)
		(pad "A24" smd rect
			(at 2.29997 5.804916 90)
			(size 0.381 1.27)
			(layers "F.Cu" "F.Mask" "F.Paste")
			(net "P5E_PEX1_STN2_RX_DP<46>")
		)
		(pad "A25" smd rect
			(at 2.29997 6.405118 90)
			(size 0.381 1.27)
			(layers "F.Cu" "F.Mask" "F.Paste")
			(net "GND")
		)
		(pad "A26" smd rect
			(at 2.29997 7.005066 90)
			(size 0.381 1.27)
			(layers "F.Cu" "F.Mask" "F.Paste")
			(net "P5E_PEX1_STN2_RX_DN<47>")
		)
		(pad "A27" smd rect
			(at 2.29997 7.605014 90)
			(size 0.381 1.27)
			(layers "F.Cu" "F.Mask" "F.Paste")
			(net "P5E_PEX1_STN2_RX_DP<47>")
		)
		(pad "A28" smd rect
			(at 2.29997 8.204962 90)
			(size 0.381 1.27)
			(layers "F.Cu" "F.Mask" "F.Paste")
			(net "GND")
		)
		(pad "B1" smd rect
			(at -2.29997 -7.994904 90)
			(size 0.381 1.27)
			(layers "F.Cu" "F.Mask" "F.Paste")
			(net "P12V_SSD4")
		)
		(pad "B2" smd rect
			(at -2.29997 -7.394956 90)
			(size 0.381 1.27)
			(layers "F.Cu" "F.Mask" "F.Paste")
			(net "P12V_SSD4")
		)
		(pad "B3" smd rect
			(at -2.29997 -6.795008 90)
			(size 0.381 1.27)
			(layers "F.Cu" "F.Mask" "F.Paste")
			(net "P12V_SSD4")
		)
		(pad "B4" smd rect
			(at -2.29997 -6.19506 90)
			(size 0.381 1.27)
			(layers "F.Cu" "F.Mask" "F.Paste")
			(net "P12V_SSD4")
		)
		(pad "B5" smd rect
			(at -2.29997 -5.595112 90)
			(size 0.381 1.27)
			(layers "F.Cu" "F.Mask" "F.Paste")
			(net "P12V_SSD4")
		)
		(pad "B6" smd rect
			(at -2.29997 -4.99491 90)
			(size 0.381 1.27)
			(layers "F.Cu" "F.Mask" "F.Paste")
			(net "P12V_SSD4")
		)
		(pad "B7" smd rect
			(at -2.29997 -4.394962 90)
			(size 0.381 1.27)
			(layers "F.Cu" "F.Mask" "F.Paste")
			(net "Net_8526")
		)
		(pad "B8" smd rect
			(at -2.29997 -3.795014 90)
			(size 0.381 1.27)
			(layers "F.Cu" "F.Mask" "F.Paste")
			(net "Net_8523")
		)
		(pad "B9" smd rect
			(at -2.29997 -3.195066 90)
			(size 0.381 1.27)
			(layers "F.Cu" "F.Mask" "F.Paste")
			(net "DUALPORT_N_SSD4")
		)
		(pad "B10" smd rect
			(at -2.29997 -2.595118 90)
			(size 0.381 1.27)
			(layers "F.Cu" "F.Mask" "F.Paste")
			(net "RST_SSD4_PERST_R_N")
		)
		(pad "B11" smd rect
			(at -2.29997 -1.994916 90)
			(size 0.381 1.27)
			(layers "F.Cu" "F.Mask" "F.Paste")
			(net "P3V3_SSD4")
		)
		(pad "B12" smd rect
			(at -2.29997 -1.394968 90)
			(size 0.381 1.27)
			(layers "F.Cu" "F.Mask" "F.Paste")
			(net "SSD4_PWRDIS_R")
		)
		(pad "B13" smd rect
			(at -2.29997 -0.79502 90)
			(size 0.381 1.27)
			(layers "F.Cu" "F.Mask" "F.Paste")
			(net "GND")
		)
		(pad "B14" smd rect
			(at -2.29997 -0.195072 90)
			(size 0.381 1.27)
			(layers "F.Cu" "F.Mask" "F.Paste")
			(net "CLK_100M_DB800ZL_SSD4_R_DN")
		)
		(pad "B15" smd rect
			(at -2.29997 0.404876 90)
			(size 0.381 1.27)
			(layers "F.Cu" "F.Mask" "F.Paste")
			(net "CLK_100M_DB800ZL_SSD4_R_DP")
		)
		(pad "B16" smd rect
			(at -2.29997 1.005078 90)
			(size 0.381 1.27)
			(layers "F.Cu" "F.Mask" "F.Paste")
			(net "GND")
		)
		(pad "B17" smd rect
			(at -2.29997 1.605026 90)
			(size 0.381 1.27)
			(layers "F.Cu" "F.Mask" "F.Paste")
			(net "P5E_PEX1_STN2_TX_C_DN<44>")
		)
		(pad "B18" smd rect
			(at -2.29997 2.204974 90)
			(size 0.381 1.27)
			(layers "F.Cu" "F.Mask" "F.Paste")
			(net "P5E_PEX1_STN2_TX_C_DP<44>")
		)
		(pad "B19" smd rect
			(at -2.29997 2.804922 90)
			(size 0.381 1.27)
			(layers "F.Cu" "F.Mask" "F.Paste")
			(net "GND")
		)
		(pad "B20" smd rect
			(at -2.29997 3.405124 90)
			(size 0.381 1.27)
			(layers "F.Cu" "F.Mask" "F.Paste")
			(net "P5E_PEX1_STN2_TX_C_DN<45>")
		)
		(pad "B21" smd rect
			(at -2.29997 4.005072 90)
			(size 0.381 1.27)
			(layers "F.Cu" "F.Mask" "F.Paste")
			(net "P5E_PEX1_STN2_TX_C_DP<45>")
		)
		(pad "B22" smd rect
			(at -2.29997 4.60502 90)
			(size 0.381 1.27)
			(layers "F.Cu" "F.Mask" "F.Paste")
			(net "GND")
		)
		(pad "B23" smd rect
			(at -2.29997 5.204968 90)
			(size 0.381 1.27)
			(layers "F.Cu" "F.Mask" "F.Paste")
			(net "P5E_PEX1_STN2_TX_C_DN<46>")
		)
		(pad "B24" smd rect
			(at -2.29997 5.804916 90)
			(size 0.381 1.27)
			(layers "F.Cu" "F.Mask" "F.Paste")
			(net "P5E_PEX1_STN2_TX_C_DP<46>")
		)
		(pad "B25" smd rect
			(at -2.29997 6.405118 90)
			(size 0.381 1.27)
			(layers "F.Cu" "F.Mask" "F.Paste")
			(net "GND")
		)
		(pad "B26" smd rect
			(at -2.29997 7.005066 90)
			(size 0.381 1.27)
			(layers "F.Cu" "F.Mask" "F.Paste")
			(net "P5E_PEX1_STN2_TX_C_DN<47>")
		)
		(pad "B27" smd rect
			(at -2.29997 7.605014 90)
			(size 0.381 1.27)
			(layers "F.Cu" "F.Mask" "F.Paste")
			(net "P5E_PEX1_STN2_TX_C_DP<47>")
		)
		(pad "B28" smd rect
			(at -2.29997 8.204962 90)
			(size 0.381 1.27)
			(layers "F.Cu" "F.Mask" "F.Paste")
			(net "GND")
		)
		(pad "G1" thru_hole oval
			(at 0 -11.364976 90)
			(size 1.6256 3.4798)
			(drill oval 1.1176 2.4638)
			(layers "*.Cu" "*.Mask")
			(remove_unused_layers no)
			(net "GND")
			(clearance 0.127)
			(thermal_gap 0.127)
		)
		(pad "G2" thru_hole oval
			(at 0 11.364976 90)
			(size 1.6256 3.4798)
			(drill oval 1.1176 2.4638)
			(layers "*.Cu" "*.Mask")
			(remove_unused_layers no)
			(net "GND")
			(clearance 0.127)
			(thermal_gap 0.127)
		)
		(zone
			(layer "F.Cu")
			(hatch none 0.5)
			(connect_pads
				(clearance 0)
			)
			(min_thickness 0.25)
			(keepout
				(tracks not_allowed)
				(vias allowed)
				(pads allowed)
				(copperpour not_allowed)
				(footprints allowed)
			)
			(placement
				(enabled no)
				(sheetname "")
			)
			(fill
				(thermal_gap 0.5)
				(thermal_bridge_width 0.5)
				(island_removal_mode 0)
			)
			(polygon
				(pts
					(xy 130.445002 -38.850062) (xy 127.694944 -38.850062) (xy 127.694944 -35.900106) (xy 130.445002 -35.900106)
				)
			)
		)
		(zone
			(layer "F.Cu")
			(hatch none 0.5)
			(connect_pads
				(clearance 0)
			)
			(min_thickness 0.25)
			(keepout
				(tracks not_allowed)
				(vias allowed)
				(pads allowed)
				(copperpour not_allowed)
				(footprints allowed)
			)
			(placement
				(enabled no)
				(sheetname "")
			)
			(fill
				(thermal_gap 0.5)
				(thermal_bridge_width 0.5)
				(island_removal_mode 0)
			)
			(polygon
				(pts
					(xy 131.515104 -17.670018) (xy 127.685038 -17.670018) (xy 127.685038 -14.720062) (xy 131.515104 -14.720062)
				)
			)
		)
		(zone
			(layers "F.Cu" "B.Cu" "In1.Cu" "In2.Cu" "In3.Cu" "In4.Cu" "In5.Cu" "In6.Cu"
				"In7.Cu" "In8.Cu" "In9.Cu" "In10.Cu" "In11.Cu" "In12.Cu" "In13.Cu" "In14.Cu"
				"In15.Cu" "In16.Cu"
			)
			(hatch none 0.5)
			(connect_pads
				(clearance 0)
			)
			(min_thickness 0.25)
			(keepout
				(tracks not_allowed)
				(vias allowed)
				(pads allowed)
				(copperpour not_allowed)
				(footprints allowed)
			)
			(placement
				(enabled no)
				(sheetname "")
			)
			(fill
				(thermal_gap 0.5)
				(thermal_bridge_width 0.5)
				(island_removal_mode 0)
			)
			(polygon
				(pts
					(arc
						(start 130.03022 -36.60013)
						(mid 128.09982 -36.60013)
						(end 130.03022 -36.60013)
					)
				)
			)
		)
		(zone
			(layers "F.Cu" "B.Cu" "In1.Cu" "In2.Cu" "In3.Cu" "In4.Cu" "In5.Cu" "In6.Cu"
				"In7.Cu" "In8.Cu" "In9.Cu" "In10.Cu" "In11.Cu" "In12.Cu" "In13.Cu" "In14.Cu"
				"In15.Cu" "In16.Cu"
			)
			(hatch none 0.5)
			(connect_pads
				(clearance 0)
			)
			(min_thickness 0.25)
			(keepout
				(tracks not_allowed)
				(vias allowed)
				(pads allowed)
				(copperpour not_allowed)
				(footprints allowed)
			)
			(placement
				(enabled no)
				(sheetname "")
			)
			(fill
				(thermal_gap 0.5)
				(thermal_bridge_width 0.5)
				(island_removal_mode 0)
			)
			(polygon
				(pts
					(arc
						(start 131.78028 -16.969994)
						(mid 129.84988 -16.969994)
						(end 131.78028 -16.969994)
					)
				)
			)
		)
	)
	(footprint ""
		(layer "F.Cu")
		(at 338.074 -181.991 180)
		(property "Reference" "R4750"
			(at 0 0 180)
			(layer "F.SilkS")
			(hide yes)
			(effects
				(font
					(size 1.27 1.27)
				)
			)
		)
		(property "Value" ""
			(at 0 0 180)
			(layer "F.Fab")
			(effects
				(font
					(size 1.27 1.27)
				)
			)
		)
		(duplicate_pad_numbers_are_jumpers no)
		(fp_line
			(start 0.7874 0.4064)
			(end -0.7874 0.4064)
			(stroke
				(width 0.1524)
				(type default)
			)
			(layer "F.SilkS")
		)
		(fp_line
			(start 0.7874 -0.4064)
			(end 0.7874 0.4064)
			(stroke
				(width 0.1524)
				(type default)
			)
			(layer "F.SilkS")
		)
		(fp_line
			(start -0.7874 0.4064)
			(end -0.7874 -0.4064)
			(stroke
				(width 0.1524)
				(type default)
			)
			(layer "F.SilkS")
		)
		(fp_line
			(start -0.7874 -0.4064)
			(end 0.7874 -0.4064)
			(stroke
				(width 0.1524)
				(type default)
			)
			(layer "F.SilkS")
		)
		(fp_line
			(start 0.67945 0.3048)
			(end 0.120396 0.3048)
			(stroke
				(width 0.1)
				(type default)
			)
			(layer "F.Fab")
		)
		(fp_line
			(start 0.67945 -0.3048)
			(end 0.67945 0.3048)
			(stroke
				(width 0.1)
				(type default)
			)
			(layer "F.Fab")
		)
		(fp_line
			(start 0.12065 -0.2794)
			(end 0.12065 -0.3048)
			(stroke
				(width 0.1)
				(type default)
			)
			(layer "F.Fab")
		)
		(fp_line
			(start 0.12065 -0.3048)
			(end 0.67945 -0.3048)
			(stroke
				(width 0.1)
				(type default)
			)
			(layer "F.Fab")
		)
		(fp_line
			(start 0.120396 0.3048)
			(end 0.120396 0.2794)
			(stroke
				(width 0.1)
				(type default)
			)
			(layer "F.Fab")
		)
		(fp_line
			(start 0.120396 0.2794)
			(end -0.12065 0.2794)
			(stroke
				(width 0.1)
				(type default)
			)
			(layer "F.Fab")
		)
		(fp_line
			(start -0.12065 0.3048)
			(end -0.67945 0.3048)
			(stroke
				(width 0.1)
				(type default)
			)
			(layer "F.Fab")
		)
		(fp_line
			(start -0.12065 0.2794)
			(end -0.12065 0.3048)
			(stroke
				(width 0.1)
				(type default)
			)
			(layer "F.Fab")
		)
		(fp_line
			(start -0.12065 -0.2794)
			(end 0.12065 -0.2794)
			(stroke
				(width 0.1)
				(type default)
			)
			(layer "F.Fab")
		)
		(fp_line
			(start -0.12065 -0.305054)
			(end -0.12065 -0.2794)
			(stroke
				(width 0.1)
				(type default)
			)
			(layer "F.Fab")
		)
		(fp_line
			(start -0.67945 0.3048)
			(end -0.67945 -0.305054)
			(stroke
				(width 0.1)
				(type default)
			)
			(layer "F.Fab")
		)
		(fp_line
			(start -0.67945 -0.305054)
			(end -0.12065 -0.305054)
			(stroke
				(width 0.1)
				(type default)
			)
			(layer "F.Fab")
		)
		(pad "1" smd circle
			(at -0.40005 0 180)
			(size 0 0)
			(layers "F.Cu" "F.Mask" "F.Paste")
			(net "SSD8_PEX_PWR_EN")
		)
		(pad "2" smd circle
			(at 0.40005 0 180)
			(size 0 0)
			(layers "F.Cu" "F.Mask" "F.Paste")
			(net "SSD8_PEX_PWR_EN_R")
		)
	)
)
